# T6G (Grand Teton) — schematic netlist excerpt (pin names and nets, part order shuffled) for the footprints in the layout excerpt that follows; sources: Cadence DE-HDL packaged netlist, KiCad conversion of 04192023_DAF0TMB3IC0_F0TG_MB_C_brd_V02_OCP.brd

C1047  Q_CAP  0.1UF 10V 10% X7S  pkg C0201  page 312 : A = P0V9_CPU0_RT3_2A ; B = GND
C65  Q_CAP  0.1UF 25V 10% EMPTY  pkg 0402  page 240 : A = HPDB_HSC_PWRGD_R ; B = GND
R1281  Q_RES  33 5% CHIP  pkg 0402LF  page 81 : A = FM_P0_PCC1_N ; B = FM_P0_PCC1_R_N

(kicad_pcb
	(version 20260206)
	(generator "pcbnew")
	(generator_version "10.0")
	(general
		(thickness 1.6)
		(legacy_teardrops no)
	)
	(paper "A4")
	(title_block
		(title "04192023_DAF0TMB3IC0_F0TG_MB_C_brd_V02_OCP.brd")
		(comment 1 "Grand Teton / footprints 6806-6808 of 8354")
	)
	(layers
		(0 "F.Cu" signal "TOP")
		(4 "In1.Cu" signal "GND")
		(6 "In2.Cu" signal "IN1")
		(8 "In3.Cu" signal "GND1")
		(10 "In4.Cu" signal "IN2")
		(12 "In5.Cu" signal "GND2")
		(14 "In6.Cu" signal "IN3")
		(16 "In7.Cu" signal "GND3")
		(18 "In8.Cu" signal "VCC")
		(20 "In9.Cu" signal "VCC1")
		(22 "In10.Cu" signal "GND4")
		(24 "In11.Cu" signal "IN4")
		(26 "In12.Cu" signal "GND5")
		(28 "In13.Cu" signal "IN5")
		(30 "In14.Cu" signal "GND6")
		(32 "In15.Cu" signal "IN6")
		(34 "In16.Cu" signal "GND7")
		(2 "B.Cu" signal "BOTTOM")
		(9 "F.Adhes" user "F.Adhesive")
		(11 "B.Adhes" user "B.Adhesive")
		(13 "F.Paste" user "Package Geometry/Pastemask Top")
		(15 "B.Paste" user "Package Geometry/Pastemask Bottom")
		(5 "F.SilkS" user "Ref Des/Silkscreen Top")
		(7 "B.SilkS" user "Ref Des/Silkscreen Bottom")
		(1 "F.Mask" user "Board Geometry/Soldermask Top")
		(3 "B.Mask" user "Board Geometry/Soldermask Bottom")
		(17 "Dwgs.User" user "User.Drawings")
		(19 "Cmts.User" user "User.Comments")
		(21 "Eco1.User" user "User.Eco1")
		(23 "Eco2.User" user "User.Eco2")
		(25 "Edge.Cuts" user "Board Geometry/Outline")
		(27 "Margin" user)
		(31 "F.CrtYd" user "Package Geometry/Place Bound Top")
		(29 "B.CrtYd" user "Package Geometry/Place Bound Bottom")
		(35 "F.Fab" user "Ref Des/Assembly Top")
		(33 "B.Fab" user "Ref Des/Assembly Bottom")
	)
	(footprint ""
		(layer "B.Cu")
		(at 234.644692 -422.849548 90)
		(property "Reference" "C65"
			(at 0 0 90)
			(layer "B.SilkS")
			(hide yes)
			(effects
				(font
					(size 1.27 1.27)
				)
				(justify mirror)
			)
		)
		(property "Value" ""
			(at 0 0 90)
			(layer "B.Fab")
			(effects
				(font
					(size 1.27 1.27)
				)
				(justify mirror)
			)
		)
		(duplicate_pad_numbers_are_jumpers no)
		(fp_line
			(start 0.7874 -0.4064)
			(end -0.7874 -0.4064)
			(stroke
				(width 0.1524)
				(type default)
			)
			(layer "B.SilkS")
		)
		(fp_line
			(start -0.7874 -0.4064)
			(end -0.7874 0.4064)
			(stroke
				(width 0.1524)
				(type default)
			)
			(layer "B.SilkS")
		)
		(fp_line
			(start 0.7874 0.4064)
			(end 0.7874 -0.4064)
			(stroke
				(width 0.1524)
				(type default)
			)
			(layer "B.SilkS")
		)
		(fp_line
			(start -0.7874 0.4064)
			(end 0.7874 0.4064)
			(stroke
				(width 0.1524)
				(type default)
			)
			(layer "B.SilkS")
		)
		(fp_line
			(start 0.67945 -0.305054)
			(end 0.12065 -0.305054)
			(stroke
				(width 0.1)
				(type default)
			)
			(layer "B.Fab")
		)
		(fp_line
			(start 0.12065 -0.305054)
			(end 0.12065 -0.2794)
			(stroke
				(width 0.1)
				(type default)
			)
			(layer "B.Fab")
		)
		(fp_line
			(start -0.12065 -0.3048)
			(end -0.67945 -0.3048)
			(stroke
				(width 0.1)
				(type default)
			)
			(layer "B.Fab")
		)
		(fp_line
			(start -0.67945 -0.3048)
			(end -0.67945 0.3048)
			(stroke
				(width 0.1)
				(type default)
			)
			(layer "B.Fab")
		)
		(fp_line
			(start 0.12065 -0.2794)
			(end -0.12065 -0.2794)
			(stroke
				(width 0.1)
				(type default)
			)
			(layer "B.Fab")
		)
		(fp_line
			(start -0.12065 -0.2794)
			(end -0.12065 -0.3048)
			(stroke
				(width 0.1)
				(type default)
			)
			(layer "B.Fab")
		)
		(fp_line
			(start 0.12065 0.2794)
			(end 0.12065 0.3048)
			(stroke
				(width 0.1)
				(type default)
			)
			(layer "B.Fab")
		)
		(fp_line
			(start -0.120396 0.2794)
			(end 0.12065 0.2794)
			(stroke
				(width 0.1)
				(type default)
			)
			(layer "B.Fab")
		)
		(fp_line
			(start 0.67945 0.3048)
			(end 0.67945 -0.305054)
			(stroke
				(width 0.1)
				(type default)
			)
			(layer "B.Fab")
		)
		(fp_line
			(start 0.12065 0.3048)
			(end 0.67945 0.3048)
			(stroke
				(width 0.1)
				(type default)
			)
			(layer "B.Fab")
		)
		(fp_line
			(start -0.120396 0.3048)
			(end -0.120396 0.2794)
			(stroke
				(width 0.1)
				(type default)
			)
			(layer "B.Fab")
		)
		(fp_line
			(start -0.67945 0.3048)
			(end -0.120396 0.3048)
			(stroke
				(width 0.1)
				(type default)
			)
			(layer "B.Fab")
		)
		(pad "1" smd circle
			(at 0.40005 0 270)
			(size 0 0)
			(layers "B.Cu" "B.Mask" "B.Paste")
			(net "HPDB_HSC_PWRGD_R")
		)
		(pad "2" smd circle
			(at -0.40005 0 270)
			(size 0 0)
			(layers "B.Cu" "B.Mask" "B.Paste")
			(net "GND")
		)
	)
	(footprint ""
		(layer "B.Cu")
		(at 184.061608 -126.833376 90)
		(property "Reference" "R1281"
			(at 0 0 90)
			(layer "B.SilkS")
			(hide yes)
			(effects
				(font
					(size 1.27 1.27)
				)
				(justify mirror)
			)
		)
		(property "Value" ""
			(at 0 0 90)
			(layer "B.Fab")
			(effects
				(font
					(size 1.27 1.27)
				)
				(justify mirror)
			)
		)
		(duplicate_pad_numbers_are_jumpers no)
		(fp_line
			(start 0.7874 -0.4064)
			(end -0.7874 -0.4064)
			(stroke
				(width 0.1524)
				(type default)
			)
			(layer "B.SilkS")
		)
		(fp_line
			(start -0.7874 -0.4064)
			(end -0.7874 0.4064)
			(stroke
				(width 0.1524)
				(type default)
			)
			(layer "B.SilkS")
		)
		(fp_line
			(start 0.7874 0.4064)
			(end 0.7874 -0.4064)
			(stroke
				(width 0.1524)
				(type default)
			)
			(layer "B.SilkS")
		)
		(fp_line
			(start -0.7874 0.4064)
			(end 0.7874 0.4064)
			(stroke
				(width 0.1524)
				(type default)
			)
			(layer "B.SilkS")
		)
		(fp_line
			(start 0.67945 -0.305054)
			(end 0.12065 -0.305054)
			(stroke
				(width 0.1)
				(type default)
			)
			(layer "B.Fab")
		)
		(fp_line
			(start 0.12065 -0.305054)
			(end 0.12065 -0.2794)
			(stroke
				(width 0.1)
				(type default)
			)
			(layer "B.Fab")
		)
		(fp_line
			(start -0.12065 -0.3048)
			(end -0.67945 -0.3048)
			(stroke
				(width 0.1)
				(type default)
			)
			(layer "B.Fab")
		)
		(fp_line
			(start -0.67945 -0.3048)
			(end -0.67945 0.3048)
			(stroke
				(width 0.1)
				(type default)
			)
			(layer "B.Fab")
		)
		(fp_line
			(start 0.12065 -0.2794)
			(end -0.12065 -0.2794)
			(stroke
				(width 0.1)
				(type default)
			)
			(layer "B.Fab")
		)
		(fp_line
			(start -0.12065 -0.2794)
			(end -0.12065 -0.3048)
			(stroke
				(width 0.1)
				(type default)
			)
			(layer "B.Fab")
		)
		(fp_line
			(start 0.12065 0.2794)
			(end 0.12065 0.3048)
			(stroke
				(width 0.1)
				(type default)
			)
			(layer "B.Fab")
		)
		(fp_line
			(start -0.120396 0.2794)
			(end 0.12065 0.2794)
			(stroke
				(width 0.1)
				(type default)
			)
			(layer "B.Fab")
		)
		(fp_line
			(start 0.67945 0.3048)
			(end 0.67945 -0.305054)
			(stroke
				(width 0.1)
				(type default)
			)
			(layer "B.Fab")
		)
		(fp_line
			(start 0.12065 0.3048)
			(end 0.67945 0.3048)
			(stroke
				(width 0.1)
				(type default)
			)
			(layer "B.Fab")
		)
		(fp_line
			(start -0.120396 0.3048)
			(end -0.120396 0.2794)
			(stroke
				(width 0.1)
				(type default)
			)
			(layer "B.Fab")
		)
		(fp_line
			(start -0.67945 0.3048)
			(end -0.120396 0.3048)
			(stroke
				(width 0.1)
				(type default)
			)
			(layer "B.Fab")
		)
		(pad "1" smd circle
			(at 0.40005 0 270)
			(size 0 0)
			(layers "B.Cu" "B.Mask" "B.Paste")
			(net "FM_P0_PCC1_N")
		)
		(pad "2" smd circle
			(at -0.40005 0 270)
			(size 0 0)
			(layers "B.Cu" "B.Mask" "B.Paste")
			(net "FM_P0_PCC1_R_N")
		)
	)
	(footprint ""
		(layer "B.Cu")
		(at 390.51738 -396.150592 180)
		(property "Reference" "C1047"
			(at 0 0 0)
			(layer "B.SilkS")
			(hide yes)
			(effects
				(font
					(size 1.27 1.27)
				)
				(justify mirror)
			)
		)
		(property "Value" ""
			(at 0 0 0)
			(layer "B.Fab")
			(effects
				(font
					(size 1.27 1.27)
				)
				(justify mirror)
			)
		)
		(duplicate_pad_numbers_are_jumpers no)
		(fp_line
			(start 0.299974 0.150114)
			(end 0.299974 -0.150114)
			(stroke
				(width 0.1)
				(type default)
			)
			(layer "B.Fab")
		)
		(fp_line
			(start 0.299974 -0.150114)
			(end -0.299974 -0.150114)
			(stroke
				(width 0.1)
				(type default)
			)
			(layer "B.Fab")
		)
		(fp_line
			(start -0.299974 0.150114)
			(end 0.299974 0.150114)
			(stroke
				(width 0.1)
				(type default)
			)
			(layer "B.Fab")
		)
		(fp_line
			(start -0.299974 -0.150114)
			(end -0.299974 0.150114)
			(stroke
				(width 0.1)
				(type default)
			)
			(layer "B.Fab")
		)
		(pad "1" smd rect
			(at 0.2667 0)
			(size 0.3048 0.381)
			(layers "B.Cu" "B.Mask" "B.Paste")
			(net "P0V9_CPU0_RT3_2A")
		)
		(pad "2" smd rect
			(at -0.2667 0)
			(size 0.3048 0.381)
			(layers "B.Cu" "B.Mask" "B.Paste")
			(net "GND")
		)
	)
)
